FILE_TYPE = CONNECTIVITY;
{Allegro Design Entry HDL 17.4-2019 S026 (4007227) 1/17/2022}
"PAGE_NUMBER" = 265;
0"NC";
1"TDR_DIFF_85_TOP_DN"CDS_PHYS_NET_NAME"TDR_DIFF_85_TOP_DN";
2"TDR_DIFF_85_TOP_DP"CDS_PHYS_NET_NAME"TDR_DIFF_85_TOP_DP";
3"TDR_DIFF_85_IN1_DN"CDS_PHYS_NET_NAME"TDR_DIFF_85_IN1_DN";
4"TDR_DIFF_85_IN1_DP"CDS_PHYS_NET_NAME"TDR_DIFF_85_IN1_DP";
5"TDR_DIFF_85_IN2_DN"CDS_PHYS_NET_NAME"TDR_DIFF_85_IN2_DN";
6"TDR_DIFF_85_IN2_DP"CDS_PHYS_NET_NAME"TDR_DIFF_85_IN2_DP";
7"TDR_DIFF_85_IN4_DP"CDS_PHYS_NET_NAME"TDR_DIFF_85_IN4_DP";
8"TDR_DIFF_85_IN4_DN"CDS_PHYS_NET_NAME"TDR_DIFF_85_IN4_DN";
9"TDR_DIFF_85_IN5_DP"CDS_PHYS_NET_NAME"TDR_DIFF_85_IN5_DP";
10"TDR_DIFF_85_IN3_DN"CDS_PHYS_NET_NAME"TDR_DIFF_85_IN3_DN";
11"TDR_DIFF_85_IN3_DP"CDS_PHYS_NET_NAME"TDR_DIFF_85_IN3_DP";
12"TDR_DIFF_85_IN5_DN"CDS_PHYS_NET_NAME"TDR_DIFF_85_IN5_DN";
13"TDR_DIFF_85_IN6_DN"CDS_PHYS_NET_NAME"TDR_DIFF_85_IN6_DN";
14"TDR_DIFF_85_IN6_DP"CDS_PHYS_NET_NAME"TDR_DIFF_85_IN6_DP";
15"TDR_DIFF_85_BOT_DN"CDS_PHYS_NET_NAME"TDR_DIFF_85_BOT_DN";
16"TDR_DIFF_85_BOT_DP"CDS_PHYS_NET_NAME"TDR_DIFF_85_BOT_DP";
17"TDR_DIFF_80_TOP_DN"CDS_PHYS_NET_NAME"TDR_DIFF_80_TOP_DN";
18"TDR_DIFF_80_TOP_DP"CDS_PHYS_NET_NAME"TDR_DIFF_80_TOP_DP";
19"TDR_DIFF_80_IN1_DN"CDS_PHYS_NET_NAME"TDR_DIFF_80_IN1_DN";
20"TDR_DIFF_80_IN1_DP"CDS_PHYS_NET_NAME"TDR_DIFF_80_IN1_DP";
21"TDR_DIFF_80_IN2_DN"CDS_PHYS_NET_NAME"TDR_DIFF_80_IN2_DN";
22"TDR_DIFF_80_IN2_DP"CDS_PHYS_NET_NAME"TDR_DIFF_80_IN2_DP";
23"TDR_DIFF_80_IN3_DN"CDS_PHYS_NET_NAME"TDR_DIFF_80_IN3_DN";
24"TDR_DIFF_80_IN3_DP"CDS_PHYS_NET_NAME"TDR_DIFF_80_IN3_DP";
25"TDR_DIFF_80_IN4_DN"CDS_PHYS_NET_NAME"TDR_DIFF_80_IN4_DN";
26"TDR_DIFF_80_IN4_DP"CDS_PHYS_NET_NAME"TDR_DIFF_80_IN4_DP";
27"TDR_DIFF_80_IN5_DN"CDS_PHYS_NET_NAME"TDR_DIFF_80_IN5_DN";
28"TDR_DIFF_80_IN5_DP"CDS_PHYS_NET_NAME"TDR_DIFF_80_IN5_DP";
29"TDR_DIFF_80_IN6_DN"CDS_PHYS_NET_NAME"TDR_DIFF_80_IN6_DN";
30"TDR_DIFF_80_IN6_DP"CDS_PHYS_NET_NAME"TDR_DIFF_80_IN6_DP";
31"TDR_DIFF_80_BOT_DN"CDS_PHYS_NET_NAME"TDR_DIFF_80_BOT_DN";
32"TDR_DIFF_80_BOT_DP"CDS_PHYS_NET_NAME"TDR_DIFF_80_BOT_DP";
33"TDR_SE_50_OHM_TOP"CDS_PHYS_NET_NAME"TDR_SE_50_OHM_TOP";
34"TDR_SE_50_OHM_IN2"CDS_PHYS_NET_NAME"TDR_SE_50_OHM_IN2";
35"TDR_SE_50_OHM_IN1"CDS_PHYS_NET_NAME"TDR_SE_50_OHM_IN1";
36"TDR_SE_50_OHM_IN3"CDS_PHYS_NET_NAME"TDR_SE_50_OHM_IN3";
37"TDR_SE_50_OHM_IN5"CDS_PHYS_NET_NAME"TDR_SE_50_OHM_IN5";
38"TDR_SE_50_OHM_BOT"CDS_PHYS_NET_NAME"TDR_SE_50_OHM_BOT";
39"TDR_SE_50_OHM_IN4"CDS_PHYS_NET_NAME"TDR_SE_50_OHM_IN4";
40"TDR_SE_50_OHM_IN6"CDS_PHYS_NET_NAME"TDR_SE_50_OHM_IN6";
41"TDR_SE_45_OHM_IN4"CDS_PHYS_NET_NAME"TDR_SE_45_OHM_IN4";
42"TDR_SE_45_OHM_IN5"CDS_PHYS_NET_NAME"TDR_SE_45_OHM_IN5";
43"TDR_SE_45_OHM_BOT"CDS_PHYS_NET_NAME"TDR_SE_45_OHM_BOT";
44"TDR_SE_45_OHM_IN6"CDS_PHYS_NET_NAME"TDR_SE_45_OHM_IN6";
45"TDR_SE_45_OHM_IN3"CDS_PHYS_NET_NAME"TDR_SE_45_OHM_IN3";
46"TDR_SE_45_OHM_IN1"CDS_PHYS_NET_NAME"TDR_SE_45_OHM_IN1";
47"TDR_SE_45_OHM_TOP"CDS_PHYS_NET_NAME"TDR_SE_45_OHM_TOP";
48"TDR_SE_45_OHM_IN2"CDS_PHYS_NET_NAME"TDR_SE_45_OHM_IN2";
49"T1_GND\g";
50"T1_GND\g";
51"T1_GND\g";
52"T1_GND\g";
53"T1_GND\g";
54"T1_GND\g";
55"T1_GND\g";
56"T1_GND\g";
57"T1_GND\g";
58"T1_GND\g";
59"T1_GND\g";
60"T1_GND\g";
61"T1_GND\g";
62"T1_GND\g";
63"T1_GND\g";
64"T1_GND\g";
65"T1_GND\g";
66"T1_GND\g";
67"T1_GND\g";
68"T1_GND\g";
69"T1_GND\g";
70"T1_GND\g";
71"T1_GND\g";
72"T1_GND\g";
73"T1_GND\g";
74"T1_GND\g";
75"T1_GND\g";
76"T1_GND\g";
77"T1_GND\g";
78"T1_GND\g";
79"T1_GND\g";
80"T1_GND\g";
81"T1_GND\g";
82"T1_GND\g";
83"T1_GND\g";
84"T1_GND\g";
85"T1_GND\g";
86"T1_GND\g";
87"T1_GND\g";
88"T1_GND\g";
89"T1_GND\g";
90"T1_GND\g";
91"T1_GND\g";
92"T1_GND\g";
93"T1_GND\g";
94"T1_GND\g";
95"T1_GND\g";
96"T1_GND\g";
%"UNIVERSAL_GND"
"1","(-9050,1950)","0","pure_quanta_power","I1";
;
HDL_POWER"T1_GND"
CDS_LIB"pure_quanta_power";
"A"49;
%"UNIVERSAL_GND"
"1","(-9000,4600)","0","pure_quanta_power","I10";
;
HDL_POWER"T1_GND"
CDS_LIB"pure_quanta_power";
"A"50;
%"UNIVERSAL_GND"
"1","(-9000,5125)","0","pure_quanta_power","I11";
;
HDL_POWER"T1_GND"
CDS_LIB"pure_quanta_power";
"A"51;
%"TDR_3P"
"2","(-8650,4300)","0","pure_quanta","I12";
;
LOCATION"DB4"
$SEC"1"
CDS_SEC"1"
PACK_TYPE"TH2"
CDS_LMAN_SYM_OUTLINE"-150,100,50,-100"
CDS_LIB"pure_quanta"
MATERIAL"EMPTY"
PART_NUMBER"N_A";
"IO2 \B"
$PN"3"45;
"IO1 \B"
$PN"2"45;
"GND"
$PN"1"83;
%"TDR_3P"
"2","(-8650,4825)","0","pure_quanta","I13";
;
LOCATION"DB3"
$SEC"1"
CDS_SEC"1"
PACK_TYPE"TH2"
CDS_LMAN_SYM_OUTLINE"-150,100,50,-100"
CDS_LIB"pure_quanta"
MATERIAL"EMPTY"
PART_NUMBER"N_A";
"IO2 \B"
$PN"3"48;
"IO1 \B"
$PN"2"48;
"GND"
$PN"1"50;
%"UNIVERSAL_GND"
"1","(-9000,5650)","0","pure_quanta_power","I14";
;
HDL_POWER"T1_GND"
CDS_LIB"pure_quanta_power";
"A"52;
%"TDR_3P"
"2","(-8650,5350)","0","pure_quanta","I15";
;
LOCATION"DB2"
$SEC"1"
CDS_SEC"1"
PACK_TYPE"TH2"
CDS_LMAN_SYM_OUTLINE"-150,100,50,-100"
CDS_LIB"pure_quanta"
MATERIAL"EMPTY"
PART_NUMBER"N_A";
"IO2 \B"
$PN"3"46;
"IO1 \B"
$PN"2"46;
"GND"
$PN"1"51;
%"TDR_3P"
"2","(-8650,5875)","0","pure_quanta","I16";
;
LOCATION"DB1"
$SEC"1"
CDS_SEC"1"
PACK_TYPE"TH2"
MATERIAL"EMPTY"
CDS_LIB"pure_quanta"
CDS_LMAN_SYM_OUTLINE"-150,100,50,-100"
PART_NUMBER"N_A";
"IO2 \B"
$PN"3"47;
"IO1 \B"
$PN"2"47;
"GND"
$PN"1"52;
%"UNIVERSAL_GND"
"1","(-7350,1950)","0","pure_quanta_power","I17";
;
HDL_POWER"T1_GND"
CDS_LIB"pure_quanta_power";
"A"53;
%"TDR_3P"
"2","(-7000,2175)","0","pure_quanta","I18";
;
LOCATION"DB12"
$SEC"1"
CDS_SEC"1"
PACK_TYPE"TH2"
CDS_LMAN_SYM_OUTLINE"-150,100,50,-100"
CDS_LIB"pure_quanta"
MATERIAL"EMPTY"
PART_NUMBER"N_A";
"IO2 \B"
$PN"3"38;
"IO1 \B"
$PN"2"38;
"GND"
$PN"1"53;
%"UNIVERSAL_GND"
"1","(-7325,2500)","0","pure_quanta_power","I19";
;
HDL_POWER"T1_GND"
CDS_LIB"pure_quanta_power";
"A"54;
%"TDR_3P"
"2","(-8700,2175)","0","pure_quanta","I2";
;
LOCATION"DB6"
$SEC"1"
CDS_SEC"1"
PACK_TYPE"TH2"
MATERIAL"EMPTY"
CDS_LIB"pure_quanta"
CDS_LMAN_SYM_OUTLINE"-150,100,50,-100"
PART_NUMBER"N_A";
"IO2 \B"
$PN"3"43;
"IO1 \B"
$PN"2"43;
"GND"
$PN"1"49;
%"TDR_3P"
"2","(-6975,2725)","0","pure_quanta","I20";
;
LOCATION"DB16"
$SEC"1"
CDS_SEC"1"
PACK_TYPE"TH2"
CDS_LMAN_SYM_OUTLINE"-150,100,50,-100"
CDS_LIB"pure_quanta"
MATERIAL"EMPTY"
PART_NUMBER"N_A";
"IO2 \B"
$PN"3"40;
"IO1 \B"
$PN"2"40;
"GND"
$PN"1"54;
%"UNIVERSAL_GND"
"1","(-7325,3025)","0","pure_quanta_power","I21";
;
HDL_POWER"T1_GND"
CDS_LIB"pure_quanta_power";
"A"55;
%"TDR_3P"
"2","(-6975,3250)","0","pure_quanta","I22";
;
LOCATION"DB15"
$SEC"1"
CDS_SEC"1"
PACK_TYPE"TH2"
MATERIAL"EMPTY"
CDS_LIB"pure_quanta"
CDS_LMAN_SYM_OUTLINE"-150,100,50,-100"
PART_NUMBER"N_A";
"IO2 \B"
$PN"3"37;
"IO1 \B"
$PN"2"37;
"GND"
$PN"1"55;
%"UNIVERSAL_GND"
"1","(-7300,3550)","0","pure_quanta_power","I23";
;
HDL_POWER"T1_GND"
CDS_LIB"pure_quanta_power";
"A"56;
%"UNIVERSAL_GND"
"1","(-7300,4075)","0","pure_quanta_power","I24";
;
HDL_POWER"T1_GND"
CDS_LIB"pure_quanta_power";
"A"57;
%"TDR_3P"
"2","(-6950,3775)","0","pure_quanta","I25";
;
LOCATION"DB11"
$SEC"1"
CDS_SEC"1"
PACK_TYPE"TH2"
CDS_LMAN_SYM_OUTLINE"-150,100,50,-100"
CDS_LIB"pure_quanta"
MATERIAL"EMPTY"
PART_NUMBER"N_A";
"IO2 \B"
$PN"3"39;
"IO1 \B"
$PN"2"39;
"GND"
$PN"1"56;
%"UNIVERSAL_GND"
"1","(-5450,425)","0","pure_quanta_power","I26";
;
HDL_POWER"T1_GND"
CDS_LIB"pure_quanta_power";
"A"58;
%"UNIVERSAL_GND"
"1","(-5450,1050)","0","pure_quanta_power","I27";
;
HDL_POWER"T1_GND"
CDS_LIB"pure_quanta_power";
"A"59;
%"UNIVERSAL_GND"
"1","(-5450,1825)","0","pure_quanta_power","I28";
;
HDL_POWER"T1_GND"
CDS_LIB"pure_quanta_power";
"A"60;
%"TP_TDR_4P_FTS"
"1","(-5025,625)","0","pure_quanta","I29";
;
LOCATION"X6"
$SEC"1"
CDS_SEC"1"
MATERIAL"EMPTY"
VALUE"TP_TDR_4P_DIP"
PACK_TYPE"TH"
CDS_LIB"pure_quanta"
NEEDS_NO_SIZE"TRUE"
PART_NUMBER"TP15";
"S1"
$PN"1"32;
"P2 \B"
$PN"3"58;
"S2"
$PN"4"31;
"P1 \B"
$PN"2"58;
%"UNIVERSAL_GND"
"1","(-9025,2500)","0","pure_quanta_power","I3";
;
HDL_POWER"T1_GND"
CDS_LIB"pure_quanta_power";
"A"61;
%"TP_TDR_4P_FTS"
"1","(-5025,1275)","0","pure_quanta","I30";
;
LOCATION"X26"
$SEC"1"
CDS_SEC"1"
VALUE"TP_TDR_4P_DIP"
PACK_TYPE"TH"
MATERIAL"EMPTY"
CDS_LIB"pure_quanta"
NEEDS_NO_SIZE"TRUE"
PART_NUMBER"TP15";
"S1"
$PN"1"30;
"P2 \B"
$PN"3"59;
"S2"
$PN"4"29;
"P1 \B"
$PN"2"59;
%"TP_TDR_4P_FTS"
"1","(-5025,2050)","0","pure_quanta","I31";
;
LOCATION"X25"
$SEC"1"
CDS_SEC"1"
MATERIAL"EMPTY"
PACK_TYPE"TH"
VALUE"TP_TDR_4P_DIP"
CDS_LIB"pure_quanta"
NEEDS_NO_SIZE"TRUE"
PART_NUMBER"TP15";
"S1"
$PN"1"28;
"P2 \B"
$PN"3"60;
"S2"
$PN"4"27;
"P1 \B"
$PN"2"60;
%"UNIVERSAL_GND"
"1","(-5450,2500)","0","pure_quanta_power","I32";
;
HDL_POWER"T1_GND"
CDS_LIB"pure_quanta_power";
"A"62;
%"UNIVERSAL_GND"
"1","(-5450,3275)","0","pure_quanta_power","I33";
;
HDL_POWER"T1_GND"
CDS_LIB"pure_quanta_power";
"A"63;
%"UNIVERSAL_GND"
"1","(-5450,4050)","0","pure_quanta_power","I34";
;
HDL_POWER"T1_GND"
CDS_LIB"pure_quanta_power";
"A"64;
%"TP_TDR_4P_FTS"
"1","(-5025,2725)","0","pure_quanta","I35";
;
LOCATION"X5"
$SEC"1"
CDS_SEC"1"
PACK_TYPE"TH"
MATERIAL"EMPTY"
VALUE"TP_TDR_4P_DIP"
CDS_LIB"pure_quanta"
NEEDS_NO_SIZE"TRUE"
PART_NUMBER"TP15";
"S1"
$PN"1"26;
"P2 \B"
$PN"3"62;
"S2"
$PN"4"25;
"P1 \B"
$PN"2"62;
%"TP_TDR_4P_FTS"
"1","(-5025,3500)","0","pure_quanta","I36";
;
LOCATION"X4"
$SEC"1"
CDS_SEC"1"
MATERIAL"EMPTY"
VALUE"TP_TDR_4P_DIP"
PACK_TYPE"TH"
CDS_LIB"pure_quanta"
NEEDS_NO_SIZE"TRUE"
PART_NUMBER"TP15";
"S1"
$PN"1"24;
"P2 \B"
$PN"3"63;
"S2"
$PN"4"23;
"P1 \B"
$PN"2"63;
%"TP_TDR_4P_FTS"
"1","(-5025,4275)","0","pure_quanta","I37";
;
LOCATION"X3"
$SEC"1"
CDS_SEC"1"
VALUE"TP_TDR_4P_DIP"
MATERIAL"EMPTY"
PACK_TYPE"TH"
CDS_LIB"pure_quanta"
NEEDS_NO_SIZE"TRUE"
PART_NUMBER"TP15";
"S1"
$PN"1"22;
"P2 \B"
$PN"3"64;
"S2"
$PN"4"21;
"P1 \B"
$PN"2"64;
%"TDR_3P"
"2","(-6950,4300)","0","pure_quanta","I38";
;
LOCATION"DB10"
$SEC"1"
CDS_SEC"1"
PACK_TYPE"TH2"
MATERIAL"EMPTY"
CDS_LIB"pure_quanta"
CDS_LMAN_SYM_OUTLINE"-150,100,50,-100"
PART_NUMBER"N_A";
"IO2 \B"
$PN"3"36;
"IO1 \B"
$PN"2"36;
"GND"
$PN"1"57;
%"UNIVERSAL_GND"
"1","(-7300,4600)","0","pure_quanta_power","I39";
;
HDL_POWER"T1_GND"
CDS_LIB"pure_quanta_power";
"A"65;
%"UNIVERSAL_GND"
"1","(-9025,3025)","0","pure_quanta_power","I4";
;
HDL_POWER"T1_GND"
CDS_LIB"pure_quanta_power";
"A"66;
%"TDR_3P"
"2","(-6950,4825)","0","pure_quanta","I40";
;
LOCATION"DB9"
$SEC"1"
CDS_SEC"1"
PACK_TYPE"TH2"
MATERIAL"EMPTY"
CDS_LIB"pure_quanta"
CDS_LMAN_SYM_OUTLINE"-150,100,50,-100"
PART_NUMBER"N_A";
"IO2 \B"
$PN"3"34;
"IO1 \B"
$PN"2"34;
"GND"
$PN"1"65;
%"UNIVERSAL_GND"
"1","(-7300,5125)","0","pure_quanta_power","I41";
;
HDL_POWER"T1_GND"
CDS_LIB"pure_quanta_power";
"A"67;
%"TDR_3P"
"2","(-6950,5350)","0","pure_quanta","I42";
;
LOCATION"DB8"
$SEC"1"
CDS_SEC"1"
PACK_TYPE"TH2"
MATERIAL"EMPTY"
CDS_LIB"pure_quanta"
CDS_LMAN_SYM_OUTLINE"-150,100,50,-100"
PART_NUMBER"N_A";
"IO2 \B"
$PN"3"35;
"IO1 \B"
$PN"2"35;
"GND"
$PN"1"67;
%"UNIVERSAL_GND"
"1","(-7300,5650)","0","pure_quanta_power","I43";
;
HDL_POWER"T1_GND"
CDS_LIB"pure_quanta_power";
"A"68;
%"TDR_3P"
"2","(-6950,5875)","0","pure_quanta","I44";
;
LOCATION"DB7"
$SEC"1"
CDS_SEC"1"
PACK_TYPE"TH2"
CDS_LMAN_SYM_OUTLINE"-150,100,50,-100"
CDS_LIB"pure_quanta"
MATERIAL"EMPTY"
PART_NUMBER"N_A";
"IO2 \B"
$PN"3"33;
"IO1 \B"
$PN"2"33;
"GND"
$PN"1"68;
%"UNIVERSAL_GND"
"1","(-5450,4825)","0","pure_quanta_power","I45";
;
HDL_POWER"T1_GND"
CDS_LIB"pure_quanta_power";
"A"69;
%"UNIVERSAL_GND"
"1","(-5450,5600)","0","pure_quanta_power","I46";
;
HDL_POWER"T1_GND"
CDS_LIB"pure_quanta_power";
"A"70;
%"TP_TDR_4P_FTS"
"1","(-5025,5050)","0","pure_quanta","I47";
;
LOCATION"X2"
$SEC"1"
CDS_SEC"1"
MATERIAL"EMPTY"
PACK_TYPE"TH"
VALUE"TP_TDR_4P_DIP"
NEEDS_NO_SIZE"TRUE"
CDS_LIB"pure_quanta"
PART_NUMBER"TP15";
"S1"
$PN"1"20;
"P2 \B"
$PN"3"69;
"S2"
$PN"4"19;
"P1 \B"
$PN"2"69;
%"TP_TDR_4P_FTS"
"1","(-5025,5825)","0","pure_quanta","I48";
;
LOCATION"X1"
$SEC"1"
CDS_SEC"1"
MATERIAL"EMPTY"
PACK_TYPE"TH"
VALUE"TP_TDR_4P_DIP"
NEEDS_NO_SIZE"TRUE"
CDS_LIB"pure_quanta"
PART_NUMBER"TP15";
"S1"
$PN"1"18;
"P2 \B"
$PN"3"70;
"S2"
$PN"4"17;
"P1 \B"
$PN"2"70;
%"TP_TDR_4P_FTS"
"1","(-3700,625)","4","pure_quanta","I49";
;
LOCATION"X12"
$SEC"1"
CDS_SEC"1"
MATERIAL"EMPTY"
PACK_TYPE"TH"
VALUE"TP_TDR_4P_DIP"
CDS_LIB"pure_quanta"
NEEDS_NO_SIZE"TRUE"
PART_NUMBER"TP15";
"S1"
$PN"1"31;
"P2 \B"
$PN"3"71;
"S2"
$PN"4"32;
"P1 \B"
$PN"2"71;
%"TDR_3P"
"2","(-8675,2725)","0","pure_quanta","I5";
;
LOCATION"DB14"
$SEC"1"
CDS_SEC"1"
PACK_TYPE"TH2"
MATERIAL"EMPTY"
CDS_LIB"pure_quanta"
CDS_LMAN_SYM_OUTLINE"-150,100,50,-100"
PART_NUMBER"N_A";
"IO2 \B"
$PN"3"44;
"IO1 \B"
$PN"2"44;
"GND"
$PN"1"61;
%"UNIVERSAL_GND"
"1","(-3300,425)","0","pure_quanta_power","I50";
;
HDL_POWER"T1_GND"
CDS_LIB"pure_quanta_power";
"A"71;
%"UNIVERSAL_GND"
"1","(-3300,1050)","0","pure_quanta_power","I51";
;
HDL_POWER"T1_GND"
CDS_LIB"pure_quanta_power";
"A"72;
%"TP_TDR_4P_FTS"
"1","(-3700,1275)","4","pure_quanta","I52";
;
LOCATION"X28"
$SEC"1"
CDS_SEC"1"
PACK_TYPE"TH"
MATERIAL"EMPTY"
VALUE"TP_TDR_4P_DIP"
CDS_LIB"pure_quanta"
NEEDS_NO_SIZE"TRUE"
PART_NUMBER"TP15";
"S1"
$PN"1"29;
"P2 \B"
$PN"3"72;
"S2"
$PN"4"30;
"P1 \B"
$PN"2"72;
%"TP_TDR_4P_FTS"
"1","(-3700,2050)","4","pure_quanta","I53";
;
LOCATION"X27"
$SEC"1"
CDS_SEC"1"
PACK_TYPE"TH"
VALUE"TP_TDR_4P_DIP"
MATERIAL"EMPTY"
CDS_LIB"pure_quanta"
NEEDS_NO_SIZE"TRUE"
PART_NUMBER"TP15";
"S1"
$PN"1"27;
"P2 \B"
$PN"3"73;
"S2"
$PN"4"28;
"P1 \B"
$PN"2"73;
%"UNIVERSAL_GND"
"1","(-3300,1825)","0","pure_quanta_power","I54";
;
HDL_POWER"T1_GND"
CDS_LIB"pure_quanta_power";
"A"73;
%"UNIVERSAL_GND"
"1","(-2625,450)","0","pure_quanta_power","I55";
;
HDL_POWER"T1_GND"
CDS_LIB"pure_quanta_power";
"A"74;
%"TP_TDR_4P_FTS"
"1","(-2200,650)","0","pure_quanta","I56";
;
LOCATION"X8006"
$SEC"1"
CDS_SEC"1"
MATERIAL"EMPTY"
PACK_TYPE"TH"
VALUE"TP_TDR_4P_DIP"
CDS_LIB"pure_quanta"
NEEDS_NO_SIZE"TRUE"
PART_NUMBER"TP15";
"S1"
$PN"1"16;
"P2 \B"
$PN"3"74;
"S2"
$PN"4"15;
"P1 \B"
$PN"2"74;
%"UNIVERSAL_GND"
"1","(-2625,1075)","0","pure_quanta_power","I57";
;
HDL_POWER"T1_GND"
CDS_LIB"pure_quanta_power";
"A"75;
%"TP_TDR_4P_FTS"
"1","(-2200,1300)","0","pure_quanta","I58";
;
LOCATION"X8026"
$SEC"1"
CDS_SEC"1"
MATERIAL"EMPTY"
PACK_TYPE"TH"
VALUE"TP_TDR_4P_DIP"
CDS_LIB"pure_quanta"
NEEDS_NO_SIZE"TRUE"
PART_NUMBER"TP15";
"S1"
$PN"1"14;
"P2 \B"
$PN"3"75;
"S2"
$PN"4"13;
"P1 \B"
$PN"2"75;
%"UNIVERSAL_GND"
"1","(-2625,1850)","0","pure_quanta_power","I59";
;
HDL_POWER"T1_GND"
CDS_LIB"pure_quanta_power";
"A"76;
%"UNIVERSAL_GND"
"1","(-9000,3550)","0","pure_quanta_power","I6";
;
HDL_POWER"T1_GND"
CDS_LIB"pure_quanta_power";
"A"77;
%"TP_TDR_4P_FTS"
"1","(-2200,2075)","0","pure_quanta","I60";
;
LOCATION"X8025"
$SEC"1"
CDS_SEC"1"
MATERIAL"EMPTY"
VALUE"TP_TDR_4P_DIP"
PACK_TYPE"TH"
CDS_LIB"pure_quanta"
NEEDS_NO_SIZE"TRUE"
PART_NUMBER"TP15";
"S1"
$PN"1"9;
"P2 \B"
$PN"3"76;
"S2"
$PN"4"12;
"P1 \B"
$PN"2"76;
%"TP_TDR_4P_FTS"
"1","(-3700,3500)","4","pure_quanta","I61";
;
LOCATION"X10"
$SEC"1"
CDS_SEC"1"
MATERIAL"EMPTY"
VALUE"TP_TDR_4P_DIP"
PACK_TYPE"TH"
CDS_LIB"pure_quanta"
NEEDS_NO_SIZE"TRUE"
PART_NUMBER"TP15";
"S1"
$PN"1"23;
"P2 \B"
$PN"3"78;
"S2"
$PN"4"24;
"P1 \B"
$PN"2"78;
%"TP_TDR_4P_FTS"
"1","(-3700,4275)","4","pure_quanta","I62";
;
LOCATION"X9"
$SEC"1"
CDS_SEC"1"
VALUE"TP_TDR_4P_DIP"
MATERIAL"EMPTY"
PACK_TYPE"TH"
CDS_LIB"pure_quanta"
NEEDS_NO_SIZE"TRUE"
PART_NUMBER"TP15";
"S1"
$PN"1"21;
"P2 \B"
$PN"3"79;
"S2"
$PN"4"22;
"P1 \B"
$PN"2"79;
%"UNIVERSAL_GND"
"1","(-3300,3275)","0","pure_quanta_power","I63";
;
HDL_POWER"T1_GND"
CDS_LIB"pure_quanta_power";
"A"78;
%"UNIVERSAL_GND"
"1","(-3300,4050)","0","pure_quanta_power","I64";
;
HDL_POWER"T1_GND"
CDS_LIB"pure_quanta_power";
"A"79;
%"UNIVERSAL_GND"
"1","(-2625,2525)","0","pure_quanta_power","I65";
;
HDL_POWER"T1_GND"
CDS_LIB"pure_quanta_power";
"A"80;
%"TP_TDR_4P_FTS"
"1","(-2200,2750)","0","pure_quanta","I66";
;
LOCATION"X8005"
$SEC"1"
CDS_SEC"1"
MATERIAL"EMPTY"
VALUE"TP_TDR_4P_DIP"
PACK_TYPE"TH"
CDS_LIB"pure_quanta"
NEEDS_NO_SIZE"TRUE"
PART_NUMBER"TP15";
"S1"
$PN"1"7;
"P2 \B"
$PN"3"80;
"S2"
$PN"4"8;
"P1 \B"
$PN"2"80;
%"UNIVERSAL_GND"
"1","(-2625,3300)","0","pure_quanta_power","I67";
;
HDL_POWER"T1_GND"
CDS_LIB"pure_quanta_power";
"A"81;
%"TP_TDR_4P_FTS"
"1","(-2200,3525)","0","pure_quanta","I68";
;
LOCATION"X8004"
$SEC"1"
CDS_SEC"1"
VALUE"TP_TDR_4P_DIP"
PACK_TYPE"TH"
MATERIAL"EMPTY"
CDS_LIB"pure_quanta"
NEEDS_NO_SIZE"TRUE"
PART_NUMBER"TP15";
"S1"
$PN"1"11;
"P2 \B"
$PN"3"81;
"S2"
$PN"4"10;
"P1 \B"
$PN"2"81;
%"UNIVERSAL_GND"
"1","(-2625,4075)","0","pure_quanta_power","I69";
;
HDL_POWER"T1_GND"
CDS_LIB"pure_quanta_power";
"A"82;
%"UNIVERSAL_GND"
"1","(-9000,4075)","0","pure_quanta_power","I7";
;
HDL_POWER"T1_GND"
CDS_LIB"pure_quanta_power";
"A"83;
%"TP_TDR_4P_FTS"
"1","(-2200,4300)","0","pure_quanta","I70";
;
LOCATION"X8003"
$SEC"1"
CDS_SEC"1"
PACK_TYPE"TH"
VALUE"TP_TDR_4P_DIP"
MATERIAL"EMPTY"
CDS_LIB"pure_quanta"
NEEDS_NO_SIZE"TRUE"
PART_NUMBER"TP15";
"S1"
$PN"1"6;
"P2 \B"
$PN"3"82;
"S2"
$PN"4"5;
"P1 \B"
$PN"2"82;
%"UNIVERSAL_GND"
"1","(-475,450)","0","pure_quanta_power","I71";
;
HDL_POWER"T1_GND"
CDS_LIB"pure_quanta_power";
"A"84;
%"UNIVERSAL_GND"
"1","(-475,1075)","0","pure_quanta_power","I72";
;
HDL_POWER"T1_GND"
CDS_LIB"pure_quanta_power";
"A"85;
%"TP_TDR_4P_FTS"
"1","(-875,1300)","4","pure_quanta","I73";
;
LOCATION"X8028"
$SEC"1"
CDS_SEC"1"
VALUE"TP_TDR_4P_DIP"
PACK_TYPE"TH"
MATERIAL"EMPTY"
CDS_LIB"pure_quanta"
NEEDS_NO_SIZE"TRUE"
PART_NUMBER"TP15";
"S1"
$PN"1"13;
"P2 \B"
$PN"3"85;
"S2"
$PN"4"14;
"P1 \B"
$PN"2"85;
%"TP_TDR_4P_FTS"
"1","(-875,2075)","4","pure_quanta","I74";
;
LOCATION"X8027"
$SEC"1"
CDS_SEC"1"
VALUE"TP_TDR_4P_DIP"
MATERIAL"EMPTY"
PACK_TYPE"TH"
CDS_LIB"pure_quanta"
NEEDS_NO_SIZE"TRUE"
PART_NUMBER"TP15";
"S1"
$PN"1"12;
"P2 \B"
$PN"3"86;
"S2"
$PN"4"9;
"P1 \B"
$PN"2"86;
%"UNIVERSAL_GND"
"1","(-475,1850)","0","pure_quanta_power","I75";
;
HDL_POWER"T1_GND"
CDS_LIB"pure_quanta_power";
"A"86;
%"TP_TDR_4P_FTS"
"1","(-875,2750)","4","pure_quanta","I76";
;
LOCATION"X8011"
$SEC"1"
CDS_SEC"1"
VALUE"TP_TDR_4P_DIP"
PACK_TYPE"TH"
MATERIAL"EMPTY"
CDS_LIB"pure_quanta"
NEEDS_NO_SIZE"TRUE"
PART_NUMBER"TP15";
"S1"
$PN"1"8;
"P2 \B"
$PN"3"87;
"S2"
$PN"4"7;
"P1 \B"
$PN"2"87;
%"UNIVERSAL_GND"
"1","(-475,2525)","0","pure_quanta_power","I77";
;
HDL_POWER"T1_GND"
CDS_LIB"pure_quanta_power";
"A"87;
%"TP_TDR_4P_FTS"
"1","(-875,3525)","4","pure_quanta","I78";
;
LOCATION"X8010"
$SEC"1"
CDS_SEC"1"
MATERIAL"EMPTY"
PACK_TYPE"TH"
VALUE"TP_TDR_4P_DIP"
CDS_LIB"pure_quanta"
NEEDS_NO_SIZE"TRUE"
PART_NUMBER"TP15";
"S1"
$PN"1"10;
"P2 \B"
$PN"3"88;
"S2"
$PN"4"11;
"P1 \B"
$PN"2"88;
%"TP_TDR_4P_FTS"
"1","(-875,4300)","4","pure_quanta","I79";
;
LOCATION"X8009"
$SEC"1"
CDS_SEC"1"
VALUE"TP_TDR_4P_DIP"
MATERIAL"EMPTY"
PACK_TYPE"TH"
CDS_LIB"pure_quanta"
NEEDS_NO_SIZE"TRUE"
PART_NUMBER"TP15";
"S1"
$PN"1"5;
"P2 \B"
$PN"3"89;
"S2"
$PN"4"6;
"P1 \B"
$PN"2"89;
%"TDR_3P"
"2","(-8675,3250)","0","pure_quanta","I8";
;
LOCATION"DB13"
$SEC"1"
CDS_SEC"1"
PACK_TYPE"TH2"
CDS_LMAN_SYM_OUTLINE"-150,100,50,-100"
CDS_LIB"pure_quanta"
MATERIAL"EMPTY"
PART_NUMBER"N_A";
"IO2 \B"
$PN"3"42;
"IO1 \B"
$PN"2"42;
"GND"
$PN"1"66;
%"UNIVERSAL_GND"
"1","(-475,3300)","0","pure_quanta_power","I80";
;
HDL_POWER"T1_GND"
CDS_LIB"pure_quanta_power";
"A"88;
%"UNIVERSAL_GND"
"1","(-475,4075)","0","pure_quanta_power","I81";
;
HDL_POWER"T1_GND"
CDS_LIB"pure_quanta_power";
"A"89;
%"TP_TDR_4P_FTS"
"1","(-3700,5050)","4","pure_quanta","I82";
;
LOCATION"X8"
$SEC"1"
CDS_SEC"1"
VALUE"TP_TDR_4P_DIP"
PACK_TYPE"TH"
MATERIAL"EMPTY"
NEEDS_NO_SIZE"TRUE"
CDS_LIB"pure_quanta"
PART_NUMBER"TP15";
"S1"
$PN"1"19;
"P2 \B"
$PN"3"90;
"S2"
$PN"4"20;
"P1 \B"
$PN"2"90;
%"UNIVERSAL_GND"
"1","(-3300,4825)","0","pure_quanta_power","I83";
;
HDL_POWER"T1_GND"
CDS_LIB"pure_quanta_power";
"A"90;
%"TP_TDR_4P_FTS"
"1","(-3700,5825)","4","pure_quanta","I84";
;
LOCATION"X7"
$SEC"1"
CDS_SEC"1"
VALUE"TP_TDR_4P_DIP"
PACK_TYPE"TH"
MATERIAL"EMPTY"
NEEDS_NO_SIZE"TRUE"
CDS_LIB"pure_quanta"
PART_NUMBER"TP15";
"S1"
$PN"1"17;
"P2 \B"
$PN"3"91;
"S2"
$PN"4"18;
"P1 \B"
$PN"2"91;
%"UNIVERSAL_GND"
"1","(-3300,5600)","0","pure_quanta_power","I85";
;
HDL_POWER"T1_GND"
CDS_LIB"pure_quanta_power";
"A"91;
%"UNIVERSAL_GND"
"1","(-2625,4850)","0","pure_quanta_power","I86";
;
HDL_POWER"T1_GND"
CDS_LIB"pure_quanta_power";
"A"92;
%"TP_TDR_4P_FTS"
"1","(-2200,5075)","0","pure_quanta","I87";
;
LOCATION"X8002"
$SEC"1"
CDS_SEC"1"
VALUE"TP_TDR_4P_DIP"
PACK_TYPE"TH"
MATERIAL"EMPTY"
NEEDS_NO_SIZE"TRUE"
CDS_LIB"pure_quanta"
PART_NUMBER"TP15";
"S1"
$PN"1"4;
"P2 \B"
$PN"3"92;
"S2"
$PN"4"3;
"P1 \B"
$PN"2"92;
%"UNIVERSAL_GND"
"1","(-2625,5625)","0","pure_quanta_power","I88";
;
HDL_POWER"T1_GND"
CDS_LIB"pure_quanta_power";
"A"93;
%"TP_TDR_4P_FTS"
"1","(-2200,5850)","0","pure_quanta","I89";
;
LOCATION"X8001"
$SEC"1"
CDS_SEC"1"
MATERIAL"EMPTY"
PACK_TYPE"TH"
VALUE"TP_TDR_4P_DIP"
NEEDS_NO_SIZE"TRUE"
CDS_LIB"pure_quanta"
PART_NUMBER"TP15";
"S1"
$PN"1"2;
"P2 \B"
$PN"3"93;
"S2"
$PN"4"1;
"P1 \B"
$PN"2"93;
%"TDR_3P"
"2","(-8650,3775)","0","pure_quanta","I9";
;
LOCATION"DB5"
$SEC"1"
CDS_SEC"1"
PACK_TYPE"TH2"
MATERIAL"EMPTY"
CDS_LIB"pure_quanta"
CDS_LMAN_SYM_OUTLINE"-150,100,50,-100"
PART_NUMBER"N_A";
"IO2 \B"
$PN"3"41;
"IO1 \B"
$PN"2"41;
"GND"
$PN"1"77;
%"TP_TDR_4P_FTS"
"1","(-875,5075)","4","pure_quanta","I90";
;
LOCATION"X8008"
$SEC"1"
CDS_SEC"1"
PACK_TYPE"TH"
VALUE"TP_TDR_4P_DIP"
MATERIAL"EMPTY"
NEEDS_NO_SIZE"TRUE"
CDS_LIB"pure_quanta"
PART_NUMBER"TP15";
"S1"
$PN"1"3;
"P2 \B"
$PN"3"94;
"S2"
$PN"4"4;
"P1 \B"
$PN"2"94;
%"UNIVERSAL_GND"
"1","(-475,4850)","0","pure_quanta_power","I91";
;
HDL_POWER"T1_GND"
CDS_LIB"pure_quanta_power";
"A"94;
%"TP_TDR_4P_FTS"
"1","(-875,5850)","4","pure_quanta","I92";
;
LOCATION"X8007"
$SEC"1"
CDS_SEC"1"
VALUE"TP_TDR_4P_DIP"
PACK_TYPE"TH"
MATERIAL"EMPTY"
NEEDS_NO_SIZE"TRUE"
CDS_LIB"pure_quanta"
PART_NUMBER"TP15";
"S1"
$PN"1"1;
"P2 \B"
$PN"3"95;
"S2"
$PN"4"2;
"P1 \B"
$PN"2"95;
%"UNIVERSAL_GND"
"1","(-475,5625)","0","pure_quanta_power","I93";
;
HDL_POWER"T1_GND"
CDS_LIB"pure_quanta_power";
"A"95;
%"TP_TDR_4P_FTS"
"1","(-875,650)","4","pure_quanta","I94";
;
LOCATION"X8012"
$SEC"1"
CDS_SEC"1"
VALUE"TP_TDR_4P_DIP"
PACK_TYPE"TH"
MATERIAL"EMPTY"
CDS_LIB"pure_quanta"
NEEDS_NO_SIZE"TRUE"
PART_NUMBER"TP15";
"S1"
$PN"1"15;
"P2 \B"
$PN"3"84;
"S2"
$PN"4"16;
"P1 \B"
$PN"2"84;
%"UNIVERSAL_GND"
"1","(-3300,2500)","0","pure_quanta_power","I95";
;
HDL_POWER"T1_GND"
CDS_LIB"pure_quanta_power";
"A"96;
%"TP_TDR_4P_FTS"
"1","(-3700,2725)","4","pure_quanta","I96";
;
LOCATION"X11"
$SEC"1"
CDS_SEC"1"
VALUE"TP_TDR_4P_DIP"
MATERIAL"EMPTY"
PACK_TYPE"TH"
CDS_LIB"pure_quanta"
NEEDS_NO_SIZE"TRUE"
PART_NUMBER"TP15";
"S1"
$PN"1"25;
"P2 \B"
$PN"3"96;
"S2"
$PN"4"26;
"P1 \B"
$PN"2"96;
END.
